(kicad_pcb
	(version 20260206)
	(generator "pcbnew")
	(generator_version "10.0")
	(general
		(thickness 1.6)
		(legacy_teardrops no)
	)
	(paper "A4")
	(title_block
		(title "timecard-production-celestica-r4006 — R4006-B0001-02_R01.brd")
		(comment 1 "Time Appliance Project (Time Card) / footprints 911-915 of 1113")
	)
	(layers
		(0 "F.Cu" signal "TOP")
		(4 "In1.Cu" signal "L02_GND1")
		(6 "In2.Cu" signal "L03_SIG1")
		(8 "In3.Cu" signal "L04_GND2")
		(10 "In4.Cu" signal "L05_VCC1")
		(12 "In5.Cu" signal "L06_VCC2")
		(14 "In6.Cu" signal "L07_GND3")
		(16 "In7.Cu" signal "L08_SIG2")
		(18 "In8.Cu" signal "L09_GND4")
		(2 "B.Cu" signal "BOTTOM")
		(9 "F.Adhes" user "F.Adhesive")
		(11 "B.Adhes" user "B.Adhesive")
		(13 "F.Paste" user "Package Geometry/Pastemask Top")
		(15 "B.Paste" user "Package Geometry/Pastemask Bottom")
		(5 "F.SilkS" user "Ref Des/Silkscreen Top")
		(7 "B.SilkS" user "Ref Des/Silkscreen Bottom")
		(1 "F.Mask" user "Board Geometry/Soldermask Top")
		(3 "B.Mask" user "Board Geometry/Soldermask Bottom")
		(17 "Dwgs.User" user "User.Drawings")
		(19 "Cmts.User" user "User.Comments")
		(21 "Eco1.User" user "User.Eco1")
		(23 "Eco2.User" user "User.Eco2")
		(25 "Edge.Cuts" user "Board Geometry/Outline")
		(27 "Margin" user)
		(31 "F.CrtYd" user "Package Geometry/Place Bound Top")
		(29 "B.CrtYd" user "Package Geometry/Place Bound Bottom")
		(35 "F.Fab" user "Ref Des/Assembly Top")
		(33 "B.Fab" user "Ref Des/Assembly Bottom")
	)
	(footprint ""
		(layer "B.Cu")
		(at 137.795 -16.256)
		(property "Reference" "R230"
			(at -1.397 1.43637 0)
			(unlocked yes)
			(layer "B.SilkS")
			(effects
				(font
					(size 0.7874 0.5842)
					(thickness 0.1524)
				)
				(justify mirror)
			)
		)
		(property "Value" "VAL*"
			(at -0.02032 2.13233 0)
			(unlocked yes)
			(layer "B.Fab")
			(hide yes)
			(effects
				(font
					(size 0.7874 0.5842)
					(thickness 0.1524)
				)
				(justify mirror)
			)
		)
		(property "Tolerance" "TOL*"
			(at -0.044704 3.05435 0)
			(unlocked yes)
			(layer "Cmts.User")
			(hide yes)
			(effects
				(font
					(size 0.7874 0.5842)
					(thickness 0.1524)
				)
				(justify mirror)
			)
		)
		(property "User Part Number" "PARTNUM*"
			(at -0.02032 4.024884 0)
			(unlocked yes)
			(layer "Cmts.User")
			(hide yes)
			(effects
				(font
					(size 0.7874 0.5842)
					(thickness 0.1524)
				)
				(justify mirror)
			)
		)
		(property "Device Type" "RESISTOR-G155-100R0-J0,0OHM,-"
			(at -0.008382 1.210564 0)
			(unlocked yes)
			(layer "B.Fab")
			(hide yes)
			(effects
				(font
					(size 0.7874 0.5842)
					(thickness 0.1524)
				)
				(justify mirror)
			)
		)
		(duplicate_pad_numbers_are_jumpers no)
		(fp_line
			(start -1.143 -0.5588)
			(end 1.143 -0.5588)
			(stroke
				(width 0.1)
				(type default)
			)
			(layer "B.SilkS")
		)
		(fp_line
			(start -1.143 0.5588)
			(end -1.143 -0.5588)
			(stroke
				(width 0.1)
				(type default)
			)
			(layer "B.SilkS")
		)
		(fp_line
			(start 1.143 -0.5588)
			(end 1.143 0.5588)
			(stroke
				(width 0.1)
				(type default)
			)
			(layer "B.SilkS")
		)
		(fp_line
			(start 1.143 0.5588)
			(end -1.143 0.5588)
			(stroke
				(width 0.1)
				(type default)
			)
			(layer "B.SilkS")
		)
		(fp_rect
			(start 1.143 -0.5588)
			(end -1.143 0.5588)
			(stroke
				(width 0)
				(type default)
			)
			(fill no)
			(layer "B.CrtYd")
		)
		(fp_line
			(start -0.508 -0.3048)
			(end 0.508 -0.3048)
			(stroke
				(width 0.1)
				(type default)
			)
			(layer "B.Fab")
		)
		(fp_line
			(start -0.508 0.3048)
			(end -0.508 -0.3048)
			(stroke
				(width 0.1)
				(type default)
			)
			(layer "B.Fab")
		)
		(fp_line
			(start 0.508 -0.3048)
			(end 0.508 0.3048)
			(stroke
				(width 0.1)
				(type default)
			)
			(layer "B.Fab")
		)
		(fp_line
			(start 0.508 0.3048)
			(end -0.508 0.3048)
			(stroke
				(width 0.1)
				(type default)
			)
			(layer "B.Fab")
		)
		(pad "1" smd rect
			(at 0.5334 0 180)
			(size 0.7112 0.6096)
			(layers "B.Cu" "B.Mask" "B.Paste")
			(net "UNNAMED_515_CAPACITOR_I138_1")
		)
		(pad "2" smd rect
			(at -0.5334 0 180)
			(size 0.7112 0.6096)
			(layers "B.Cu" "B.Mask" "B.Paste")
			(net "FPGA_CFG_INIT_N")
		)
		(zone
			(layer "B.Cu")
			(hatch none 0.5)
			(connect_pads
				(clearance 0)
			)
			(min_thickness 0.25)
			(keepout
				(tracks allowed)
				(vias not_allowed)
				(pads allowed)
				(copperpour not_allowed)
				(footprints allowed)
			)
			(placement
				(enabled no)
				(sheetname "")
			)
			(fill
				(thermal_gap 0.5)
				(thermal_bridge_width 0.5)
				(island_removal_mode 0)
			)
			(polygon
				(pts
					(xy 137.8712 -16.5608) (xy 137.7188 -16.5608) (xy 137.7188 -15.9512) (xy 137.8712 -15.9512)
				)
			)
		)
	)
	(footprint ""
		(layer "B.Cu")
		(at 88.519 -84.455 180)
		(property "Reference" "R192"
			(at -0.254 5.54863 0)
			(unlocked yes)
			(layer "B.SilkS")
			(effects
				(font
					(size 0.7874 0.5842)
					(thickness 0.1524)
				)
				(justify mirror)
			)
		)
		(property "Value" "VAL*"
			(at -0.02032 2.13233 180)
			(unlocked yes)
			(layer "B.Fab")
			(hide yes)
			(effects
				(font
					(size 0.7874 0.5842)
					(thickness 0.1524)
				)
				(justify mirror)
			)
		)
		(property "Tolerance" "TOL*"
			(at -0.044704 3.05435 180)
			(unlocked yes)
			(layer "Cmts.User")
			(hide yes)
			(effects
				(font
					(size 0.7874 0.5842)
					(thickness 0.1524)
				)
				(justify mirror)
			)
		)
		(property "User Part Number" "PARTNUM*"
			(at -0.02032 4.024884 180)
			(unlocked yes)
			(layer "Cmts.User")
			(hide yes)
			(effects
				(font
					(size 0.7874 0.5842)
					(thickness 0.1524)
				)
				(justify mirror)
			)
		)
		(property "Device Type" "RESISTOR-G155-14701-01,4.7KOHMA"
			(at -0.008382 1.210564 180)
			(unlocked yes)
			(layer "B.Fab")
			(hide yes)
			(effects
				(font
					(size 0.7874 0.5842)
					(thickness 0.1524)
				)
				(justify mirror)
			)
		)
		(duplicate_pad_numbers_are_jumpers no)
		(fp_line
			(start 1.143 0.5588)
			(end -1.143 0.5588)
			(stroke
				(width 0.1)
				(type default)
			)
			(layer "B.SilkS")
		)
		(fp_line
			(start 1.143 -0.5588)
			(end 1.143 0.5588)
			(stroke
				(width 0.1)
				(type default)
			)
			(layer "B.SilkS")
		)
		(fp_line
			(start -1.143 0.5588)
			(end -1.143 -0.5588)
			(stroke
				(width 0.1)
				(type default)
			)
			(layer "B.SilkS")
		)
		(fp_line
			(start -1.143 -0.5588)
			(end 1.143 -0.5588)
			(stroke
				(width 0.1)
				(type default)
			)
			(layer "B.SilkS")
		)
		(fp_rect
			(start 1.143 -0.5588)
			(end -1.143 0.5588)
			(stroke
				(width 0)
				(type default)
			)
			(fill no)
			(layer "B.CrtYd")
		)
		(fp_line
			(start 0.508 0.3048)
			(end -0.508 0.3048)
			(stroke
				(width 0.1)
				(type default)
			)
			(layer "B.Fab")
		)
		(fp_line
			(start 0.508 -0.3048)
			(end 0.508 0.3048)
			(stroke
				(width 0.1)
				(type default)
			)
			(layer "B.Fab")
		)
		(fp_line
			(start -0.508 0.3048)
			(end -0.508 -0.3048)
			(stroke
				(width 0.1)
				(type default)
			)
			(layer "B.Fab")
		)
		(fp_line
			(start -0.508 -0.3048)
			(end 0.508 -0.3048)
			(stroke
				(width 0.1)
				(type default)
			)
			(layer "B.Fab")
		)
		(pad "1" smd rect
			(at 0.5334 0)
			(size 0.7112 0.6096)
			(layers "B.Cu" "B.Mask" "B.Paste")
			(net "FLASH_CLK")
		)
		(pad "2" smd rect
			(at -0.5334 0)
			(size 0.7112 0.6096)
			(layers "B.Cu" "B.Mask" "B.Paste")
			(net "SG")
		)
		(zone
			(layer "B.Cu")
			(hatch none 0.5)
			(connect_pads
				(clearance 0)
			)
			(min_thickness 0.25)
			(keepout
				(tracks allowed)
				(vias not_allowed)
				(pads allowed)
				(copperpour not_allowed)
				(footprints allowed)
			)
			(placement
				(enabled no)
				(sheetname "")
			)
			(fill
				(thermal_gap 0.5)
				(thermal_bridge_width 0.5)
				(island_removal_mode 0)
			)
			(polygon
				(pts
					(xy 88.4428 -84.1502) (xy 88.5952 -84.1502) (xy 88.5952 -84.7598) (xy 88.4428 -84.7598)
				)
			)
		)
	)
	(footprint ""
		(layer "B.Cu")
		(at 144.018 -107.696 90)
		(property "Reference" "R259"
			(at -0.762 1.16205 270)
			(unlocked yes)
			(layer "B.SilkS")
			(effects
				(font
					(size 0.635 0.4064)
					(thickness 0.1524)
				)
				(justify mirror)
			)
		)
		(property "Value" "VAL*"
			(at -0.02032 2.13233 90)
			(unlocked yes)
			(layer "B.Fab")
			(hide yes)
			(effects
				(font
					(size 0.7874 0.5842)
					(thickness 0.1524)
				)
				(justify mirror)
			)
		)
		(property "Device Type" "RESISTOR-G155-13300-01,330OHM,A"
			(at -0.008382 1.210564 90)
			(unlocked yes)
			(layer "B.Fab")
			(hide yes)
			(effects
				(font
					(size 0.7874 0.5842)
					(thickness 0.1524)
				)
				(justify mirror)
			)
		)
		(property "User Part Number" "PARTNUM*"
			(at -0.02032 4.024884 90)
			(unlocked yes)
			(layer "Cmts.User")
			(hide yes)
			(effects
				(font
					(size 0.7874 0.5842)
					(thickness 0.1524)
				)
				(justify mirror)
			)
		)
		(property "Tolerance" "TOL*"
			(at -0.044704 3.05435 90)
			(unlocked yes)
			(layer "Cmts.User")
			(hide yes)
			(effects
				(font
					(size 0.7874 0.5842)
					(thickness 0.1524)
				)
				(justify mirror)
			)
		)
		(duplicate_pad_numbers_are_jumpers no)
		(fp_line
			(start 1.143 -0.5588)
			(end 1.143 0.5588)
			(stroke
				(width 0.1)
				(type default)
			)
			(layer "B.SilkS")
		)
		(fp_line
			(start -1.143 -0.5588)
			(end 1.143 -0.5588)
			(stroke
				(width 0.1)
				(type default)
			)
			(layer "B.SilkS")
		)
		(fp_line
			(start 1.143 0.5588)
			(end -1.143 0.5588)
			(stroke
				(width 0.1)
				(type default)
			)
			(layer "B.SilkS")
		)
		(fp_line
			(start -1.143 0.5588)
			(end -1.143 -0.5588)
			(stroke
				(width 0.1)
				(type default)
			)
			(layer "B.SilkS")
		)
		(fp_rect
			(start -1.143 -0.5588)
			(end 1.143 0.5588)
			(stroke
				(width 0)
				(type default)
			)
			(fill no)
			(layer "B.CrtYd")
		)
		(fp_line
			(start 0.508 -0.3048)
			(end 0.508 0.3048)
			(stroke
				(width 0.1)
				(type default)
			)
			(layer "B.Fab")
		)
		(fp_line
			(start -0.508 -0.3048)
			(end 0.508 -0.3048)
			(stroke
				(width 0.1)
				(type default)
			)
			(layer "B.Fab")
		)
		(fp_line
			(start 0.508 0.3048)
			(end -0.508 0.3048)
			(stroke
				(width 0.1)
				(type default)
			)
			(layer "B.Fab")
		)
		(fp_line
			(start -0.508 0.3048)
			(end -0.508 -0.3048)
			(stroke
				(width 0.1)
				(type default)
			)
			(layer "B.Fab")
		)
		(pad "1" smd rect
			(at 0.5334 0 270)
			(size 0.7112 0.6096)
			(layers "B.Cu" "B.Mask" "B.Paste")
			(net "UNNAMED_14_OPTICAL_I136_A")
		)
		(pad "2" smd rect
			(at -0.5334 0 270)
			(size 0.7112 0.6096)
			(layers "B.Cu" "B.Mask" "B.Paste")
			(net "XP3R3V_FPGA")
		)
		(zone
			(layer "B.Cu")
			(hatch none 0.5)
			(connect_pads
				(clearance 0)
			)
			(min_thickness 0.25)
			(keepout
				(tracks allowed)
				(vias not_allowed)
				(pads allowed)
				(copperpour not_allowed)
				(footprints allowed)
			)
			(placement
				(enabled no)
				(sheetname "")
			)
			(fill
				(thermal_gap 0.5)
				(thermal_bridge_width 0.5)
				(island_removal_mode 0)
			)
			(polygon
				(pts
					(xy 143.7132 -107.6198) (xy 144.3228 -107.6198) (xy 144.3228 -107.7722) (xy 143.7132 -107.7722)
				)
			)
		)
	)
	(footprint ""
		(layer "B.Cu")
		(at 38.1 -76.2)
		(property "Reference" "R491"
			(at -0.508 -1.10363 0)
			(unlocked yes)
			(layer "B.SilkS")
			(effects
				(font
					(size 0.7874 0.5842)
					(thickness 0.1524)
				)
				(justify mirror)
			)
		)
		(property "Value" "VAL*"
			(at -0.02032 2.13233 0)
			(unlocked yes)
			(layer "B.Fab")
			(hide yes)
			(effects
				(font
					(size 0.7874 0.5842)
					(thickness 0.1524)
				)
				(justify mirror)
			)
		)
		(property "Tolerance" "TOL*"
			(at -0.044704 3.05435 0)
			(unlocked yes)
			(layer "Cmts.User")
			(hide yes)
			(effects
				(font
					(size 0.7874 0.5842)
					(thickness 0.1524)
				)
				(justify mirror)
			)
		)
		(property "User Part Number" "PARTNUM*"
			(at -0.02032 4.024884 0)
			(unlocked yes)
			(layer "Cmts.User")
			(hide yes)
			(effects
				(font
					(size 0.7874 0.5842)
					(thickness 0.1524)
				)
				(justify mirror)
			)
		)
		(property "Device Type" "RESISTOR-G155-03241-01,3.24KOHA"
			(at -0.008382 1.210564 0)
			(unlocked yes)
			(layer "B.Fab")
			(hide yes)
			(effects
				(font
					(size 0.7874 0.5842)
					(thickness 0.1524)
				)
				(justify mirror)
			)
		)
		(duplicate_pad_numbers_are_jumpers no)
		(fp_line
			(start -1.143 -0.5588)
			(end 1.143 -0.5588)
			(stroke
				(width 0.1)
				(type default)
			)
			(layer "B.SilkS")
		)
		(fp_line
			(start -1.143 0.5588)
			(end -1.143 -0.5588)
			(stroke
				(width 0.1)
				(type default)
			)
			(layer "B.SilkS")
		)
		(fp_line
			(start 1.143 -0.5588)
			(end 1.143 0.5588)
			(stroke
				(width 0.1)
				(type default)
			)
			(layer "B.SilkS")
		)
		(fp_line
			(start 1.143 0.5588)
			(end -1.143 0.5588)
			(stroke
				(width 0.1)
				(type default)
			)
			(layer "B.SilkS")
		)
		(fp_poly
			(pts
				(xy 1.143 0.5588) (xy -1.143 0.5588) (xy -1.143 -0.5588) (xy 1.143 -0.5588)
			)
			(stroke
				(width 0)
				(type default)
			)
			(fill no)
			(layer "B.CrtYd")
		)
		(fp_line
			(start -0.508 -0.3048)
			(end 0.508 -0.3048)
			(stroke
				(width 0.1)
				(type default)
			)
			(layer "B.Fab")
		)
		(fp_line
			(start -0.508 0.3048)
			(end -0.508 -0.3048)
			(stroke
				(width 0.1)
				(type default)
			)
			(layer "B.Fab")
		)
		(fp_line
			(start 0.508 -0.3048)
			(end 0.508 0.3048)
			(stroke
				(width 0.1)
				(type default)
			)
			(layer "B.Fab")
		)
		(fp_line
			(start 0.508 0.3048)
			(end -0.508 0.3048)
			(stroke
				(width 0.1)
				(type default)
			)
			(layer "B.Fab")
		)
		(pad "1" smd rect
			(at 0.5334 0 180)
			(size 0.7112 0.6096)
			(layers "B.Cu" "B.Mask" "B.Paste")
			(net "UNNAMED_525_ISL80101IRAJZDFN10_")
		)
		(pad "2" smd rect
			(at -0.5334 0 180)
			(size 0.7112 0.6096)
			(layers "B.Cu" "B.Mask" "B.Paste")
			(net "SG")
		)
		(zone
			(layer "B.Cu")
			(hatch none 0.5)
			(connect_pads
				(clearance 0)
			)
			(min_thickness 0.25)
			(keepout
				(tracks allowed)
				(vias not_allowed)
				(pads allowed)
				(copperpour not_allowed)
				(footprints allowed)
			)
			(placement
				(enabled no)
				(sheetname "")
			)
			(fill
				(thermal_gap 0.5)
				(thermal_bridge_width 0.5)
				(island_removal_mode 0)
			)
			(polygon
				(pts
					(xy 38.1762 -75.8952) (xy 38.1762 -76.5048) (xy 38.0238 -76.5048) (xy 38.0238 -75.8952)
				)
			)
		)
		(zone
			(layer "B.Cu")
			(hatch none 0.5)
			(connect_pads
				(clearance 0)
			)
			(min_thickness 0.25)
			(keepout
				(tracks not_allowed)
				(vias allowed)
				(pads allowed)
				(copperpour not_allowed)
				(footprints allowed)
			)
			(placement
				(enabled no)
				(sheetname "")
			)
			(fill
				(thermal_gap 0.5)
				(thermal_bridge_width 0.5)
				(island_removal_mode 0)
			)
			(polygon
				(pts
					(xy 38.1762 -75.8952) (xy 38.1762 -76.5048) (xy 38.0238 -76.5048) (xy 38.0238 -75.8952)
				)
			)
		)
	)
	(footprint ""
		(layer "B.Cu")
		(at 66.548 -60.325)
		(property "Reference" "R267"
			(at -1.143 -1.10363 0)
			(unlocked yes)
			(layer "B.SilkS")
			(effects
				(font
					(size 0.7874 0.5842)
					(thickness 0.1524)
				)
				(justify mirror)
			)
		)
		(property "Value" "VAL*"
			(at -0.02032 2.13233 0)
			(unlocked yes)
			(layer "B.Fab")
			(hide yes)
			(effects
				(font
					(size 0.7874 0.5842)
					(thickness 0.1524)
				)
				(justify mirror)
			)
		)
		(property "Device Type" "RESISTOR-G155-133R0-01,33OHM,1%"
			(at -0.008382 1.210564 0)
			(unlocked yes)
			(layer "B.Fab")
			(hide yes)
			(effects
				(font
					(size 0.7874 0.5842)
					(thickness 0.1524)
				)
				(justify mirror)
			)
		)
		(property "User Part Number" "PARTNUM*"
			(at -0.02032 4.024884 0)
			(unlocked yes)
			(layer "Cmts.User")
			(hide yes)
			(effects
				(font
					(size 0.7874 0.5842)
					(thickness 0.1524)
				)
				(justify mirror)
			)
		)
		(property "Tolerance" "TOL*"
			(at -0.044704 3.05435 0)
			(unlocked yes)
			(layer "Cmts.User")
			(hide yes)
			(effects
				(font
					(size 0.7874 0.5842)
					(thickness 0.1524)
				)
				(justify mirror)
			)
		)
		(duplicate_pad_numbers_are_jumpers no)
		(fp_line
			(start -1.143 -0.5588)
			(end 1.143 -0.5588)
			(stroke
				(width 0.1)
				(type default)
			)
			(layer "B.SilkS")
		)
		(fp_line
			(start -1.143 0.5588)
			(end -1.143 -0.5588)
			(stroke
				(width 0.1)
				(type default)
			)
			(layer "B.SilkS")
		)
		(fp_line
			(start 1.143 -0.5588)
			(end 1.143 0.5588)
			(stroke
				(width 0.1)
				(type default)
			)
			(layer "B.SilkS")
		)
		(fp_line
			(start 1.143 0.5588)
			(end -1.143 0.5588)
			(stroke
				(width 0.1)
				(type default)
			)
			(layer "B.SilkS")
		)
		(fp_rect
			(start -1.143 0.5588)
			(end 1.143 -0.5588)
			(stroke
				(width 0)
				(type default)
			)
			(fill no)
			(layer "B.CrtYd")
		)
		(fp_line
			(start -0.508 -0.3048)
			(end 0.508 -0.3048)
			(stroke
				(width 0.1)
				(type default)
			)
			(layer "B.Fab")
		)
		(fp_line
			(start -0.508 0.3048)
			(end -0.508 -0.3048)
			(stroke
				(width 0.1)
				(type default)
			)
			(layer "B.Fab")
		)
		(fp_line
			(start 0.508 -0.3048)
			(end 0.508 0.3048)
			(stroke
				(width 0.1)
				(type default)
			)
			(layer "B.Fab")
		)
		(fp_line
			(start 0.508 0.3048)
			(end -0.508 0.3048)
			(stroke
				(width 0.1)
				(type default)
			)
			(layer "B.Fab")
		)
		(pad "1" smd rect
			(at 0.5334 0 180)
			(size 0.7112 0.6096)
			(layers "B.Cu" "B.Mask" "B.Paste")
			(net "UNNAMED_527_RESISTOR_I206_1")
		)
		(pad "2" smd rect
			(at -0.5334 0 180)
			(size 0.7112 0.6096)
			(layers "B.Cu" "B.Mask" "B.Paste")
			(net "FPGA_IN_MAC_USB_OC_N")
		)
		(zone
			(layer "B.Cu")
			(hatch none 0.5)
			(connect_pads
				(clearance 0)
			)
			(min_thickness 0.25)
			(keepout
				(tracks allowed)
				(vias not_allowed)
				(pads allowed)
				(copperpour not_allowed)
				(footprints allowed)
			)
			(placement
				(enabled no)
				(sheetname "")
			)
			(fill
				(thermal_gap 0.5)
				(thermal_bridge_width 0.5)
				(island_removal_mode 0)
			)
			(polygon
				(pts
					(xy 66.4718 -60.0202) (xy 66.6242 -60.0202) (xy 66.6242 -60.6298) (xy 66.4718 -60.6298)
				)
			)
		)
	)
)
